(kicad_pcb
	(version 20260206)
	(generator "pcbnew")
	(generator_version "10.0")
	(general
		(thickness 1.6)
		(legacy_teardrops no)
	)
	(paper "A4")
	(title_block
		(title "panther-plus-userver — 13130-1b_20150205.brd")
		(comment 1 "Honey Badger (Wiwynn) / footprints 300-306 of 1509")
	)
	(layers
		(0 "F.Cu" signal "TOP")
		(4 "In1.Cu" signal "L2")
		(6 "In2.Cu" signal "L3")
		(8 "In3.Cu" signal "L4")
		(10 "In4.Cu" signal "L5")
		(12 "In5.Cu" signal "L6")
		(14 "In6.Cu" signal "L7")
		(16 "In7.Cu" signal "L8")
		(18 "In8.Cu" signal "L9")
		(20 "In9.Cu" signal "L10")
		(22 "In10.Cu" signal "L11")
		(2 "B.Cu" signal "BOTTOM")
		(9 "F.Adhes" user "F.Adhesive")
		(11 "B.Adhes" user "B.Adhesive")
		(13 "F.Paste" user "Package Geometry/Pastemask Top")
		(15 "B.Paste" user "Package Geometry/Pastemask Bottom")
		(5 "F.SilkS" user "Ref Des/Silkscreen Top")
		(7 "B.SilkS" user "Ref Des/Silkscreen Bottom")
		(1 "F.Mask" user "Board Geometry/Soldermask Top")
		(3 "B.Mask" user "Board Geometry/Soldermask Bottom")
		(17 "Dwgs.User" user "User.Drawings")
		(19 "Cmts.User" user "User.Comments")
		(21 "Eco1.User" user "User.Eco1")
		(23 "Eco2.User" user "User.Eco2")
		(25 "Edge.Cuts" user "Board Geometry/Outline")
		(27 "Margin" user)
		(31 "F.CrtYd" user "Package Geometry/Place Bound Top")
		(29 "B.CrtYd" user "Package Geometry/Place Bound Bottom")
		(35 "F.Fab" user "Ref Des/Assembly Top")
		(33 "B.Fab" user "Ref Des/Assembly Bottom")
	)
	(footprint ""
		(layer "F.Cu")
		(at 60.706 -32.004 180)
		(property "Reference" "Q7"
			(at 0 0 180)
			(layer "F.SilkS")
			(hide yes)
			(effects
				(font
					(size 1.27 1.27)
				)
			)
		)
		(property "Value" "MMBT3904TT1G-GP"
			(at 0 -9.7282 180)
			(unlocked yes)
			(layer "F.Fab")
			(hide yes)
			(effects
				(font
					(size 1.016 1.016)
					(thickness 0.1524)
				)
			)
		)
		(property "Device Type" "SC75CBE1D6H36"
			(at 0 -11.6332 180)
			(unlocked yes)
			(layer "F.Fab")
			(hide yes)
			(effects
				(font
					(size 1.016 1.016)
					(thickness 0.1524)
				)
			)
		)
		(duplicate_pad_numbers_are_jumpers no)
		(fp_poly
			(pts
				(xy 0.381 -1.1938) (xy -0.381 -1.1938) (xy -0.381 -0.6604) (xy -1.0541 -0.6604) (xy -1.0541 0.6604)
				(xy -0.889 0.6604) (xy -0.889 1.1938) (xy 0.889 1.1938) (xy 0.889 0.6604) (xy 1.0541 0.6604) (xy 1.0541 -0.6604)
				(xy 0.381 -0.6604)
			)
			(stroke
				(width 0)
				(type default)
			)
			(fill no)
			(layer "F.CrtYd")
		)
		(fp_poly
			(pts
				(xy 0.381 -1.1938) (xy -0.381 -1.1938) (xy -0.381 -0.6604) (xy -1.0541 -0.6604) (xy -1.0541 0.6604)
				(xy -0.889 0.6604) (xy -0.889 1.1938) (xy 0.889 1.1938) (xy 0.889 0.6604) (xy 1.0541 0.6604) (xy 1.0541 -0.6604)
				(xy 0.381 -0.6604)
			)
			(stroke
				(width 0)
				(type default)
			)
			(fill no)
			(layer "F.Fab")
		)
		(pad "B" smd custom
			(at -0.508 0.6604 180)
			(size 0.127 0.127)
			(layers "F.Cu" "F.Mask" "F.Paste")
			(net "P1V8_B")
			(options
				(clearance outline)
				(anchor circle)
			)
			(primitives
				(gr_poly
					(pts
						(arc
							(start -0.0508 0.4064)
							(mid -0.194484 0.346884)
							(end -0.254 0.2032)
						)
						(arc
							(start -0.254 -0.2032)
							(mid -0.194484 -0.346884)
							(end -0.0508 -0.4064)
						)
						(arc
							(start 0.0508 -0.4064)
							(mid 0.194484 -0.346884)
							(end 0.254 -0.2032)
						)
						(arc
							(start 0.254 0.2032)
							(mid 0.194484 0.346884)
							(end 0.0508 0.4064)
						)
					)
					(width 0)
					(fill yes)
				)
			)
		)
		(pad "C" smd custom
			(at 0 -0.6604 180)
			(size 0.127 0.127)
			(layers "F.Cu" "F.Mask" "F.Paste")
			(net "P1V8_G")
			(options
				(clearance outline)
				(anchor circle)
			)
			(primitives
				(gr_poly
					(pts
						(arc
							(start -0.0508 0.4064)
							(mid -0.194484 0.346884)
							(end -0.254 0.2032)
						)
						(arc
							(start -0.254 -0.2032)
							(mid -0.194484 -0.346884)
							(end -0.0508 -0.4064)
						)
						(arc
							(start 0.0508 -0.4064)
							(mid 0.194484 -0.346884)
							(end 0.254 -0.2032)
						)
						(arc
							(start 0.254 0.2032)
							(mid 0.194484 0.346884)
							(end 0.0508 0.4064)
						)
					)
					(width 0)
					(fill yes)
				)
			)
		)
		(pad "E" smd custom
			(at 0.508 0.6604 180)
			(size 0.127 0.127)
			(layers "F.Cu" "F.Mask" "F.Paste")
			(net "GND")
			(options
				(clearance outline)
				(anchor circle)
			)
			(primitives
				(gr_poly
					(pts
						(arc
							(start -0.0508 0.4064)
							(mid -0.194484 0.346884)
							(end -0.254 0.2032)
						)
						(arc
							(start -0.254 -0.2032)
							(mid -0.194484 -0.346884)
							(end -0.0508 -0.4064)
						)
						(arc
							(start 0.0508 -0.4064)
							(mid 0.194484 -0.346884)
							(end 0.254 -0.2032)
						)
						(arc
							(start 0.254 0.2032)
							(mid 0.194484 0.346884)
							(end 0.0508 0.4064)
						)
					)
					(width 0)
					(fill yes)
				)
			)
		)
	)
	(footprint ""
		(layer "F.Cu")
		(at 113.284 -71.12 180)
		(property "Reference" "R234"
			(at 0 0 180)
			(layer "F.SilkS")
			(hide yes)
			(effects
				(font
					(size 1.27 1.27)
				)
			)
		)
		(property "Value" "4K7R2F-GP"
			(at 0.064008 -3.993896 180)
			(unlocked yes)
			(layer "F.Fab")
			(hide yes)
			(effects
				(font
					(size 1.016 1.016)
					(thickness 0.1524)
				)
			)
		)
		(property "Device Type" "R402H16"
			(at 0.064008 -5.517896 180)
			(unlocked yes)
			(layer "F.Fab")
			(hide yes)
			(effects
				(font
					(size 1.016 1.016)
					(thickness 0.1524)
				)
			)
		)
		(duplicate_pad_numbers_are_jumpers no)
		(fp_rect
			(start -0.381 0.8382)
			(end 0.381 -0.8382)
			(stroke
				(width 0)
				(type default)
			)
			(fill no)
			(layer "F.CrtYd")
		)
		(fp_rect
			(start -0.381 0.8382)
			(end 0.381 -0.8382)
			(stroke
				(width 0)
				(type default)
			)
			(fill no)
			(layer "F.Fab")
		)
		(pad "1" smd custom
			(at 0 -0.4318 180)
			(size 0.127 0.127)
			(layers "F.Cu" "F.Mask" "F.Paste")
			(net "P3V3_STBY")
			(options
				(clearance outline)
				(anchor circle)
			)
			(primitives
				(gr_poly
					(pts
						(arc
							(start -0.2032 -0.2794)
							(mid -0.239121 -0.264521)
							(end -0.254 -0.2286)
						)
						(arc
							(start -0.254 0.2286)
							(mid -0.239121 0.264521)
							(end -0.2032 0.2794)
						)
						(arc
							(start 0.2032 0.2794)
							(mid 0.239121 0.264521)
							(end 0.254 0.2286)
						)
						(arc
							(start 0.254 -0.2286)
							(mid 0.239121 -0.264521)
							(end 0.2032 -0.2794)
						)
					)
					(width 0)
					(fill yes)
				)
			)
		)
		(pad "2" smd custom
			(at 0 0.4318 180)
			(size 0.127 0.127)
			(layers "F.Cu" "F.Mask" "F.Paste")
			(net "CHA_1_SA0")
			(options
				(clearance outline)
				(anchor circle)
			)
			(primitives
				(gr_poly
					(pts
						(arc
							(start -0.2032 -0.2794)
							(mid -0.239121 -0.264521)
							(end -0.254 -0.2286)
						)
						(arc
							(start -0.254 0.2286)
							(mid -0.239121 0.264521)
							(end -0.2032 0.2794)
						)
						(arc
							(start 0.2032 0.2794)
							(mid 0.239121 0.264521)
							(end 0.254 0.2286)
						)
						(arc
							(start 0.254 -0.2286)
							(mid 0.239121 -0.264521)
							(end 0.2032 -0.2794)
						)
					)
					(width 0)
					(fill yes)
				)
			)
		)
	)
	(footprint ""
		(layer "F.Cu")
		(at 9.525 -32.004 180)
		(property "Reference" "PR206"
			(at 0 0 180)
			(layer "F.SilkS")
			(hide yes)
			(effects
				(font
					(size 1.27 1.27)
				)
			)
		)
		(property "Value" "866KR2F-GP"
			(at 1.7907 -1.1176 180)
			(unlocked yes)
			(layer "F.Fab")
			(hide yes)
			(effects
				(font
					(size 1.016 1.016)
					(thickness 0.1524)
				)
			)
		)
		(property "Device Type" "R402H16"
			(at 1.7907 -2.6416 180)
			(unlocked yes)
			(layer "F.Fab")
			(hide yes)
			(effects
				(font
					(size 1.016 1.016)
					(thickness 0.1524)
				)
			)
		)
		(duplicate_pad_numbers_are_jumpers no)
		(fp_rect
			(start -0.381 0.8382)
			(end 0.381 -0.8382)
			(stroke
				(width 0)
				(type default)
			)
			(fill no)
			(layer "F.CrtYd")
		)
		(fp_rect
			(start -0.381 0.8382)
			(end 0.381 -0.8382)
			(stroke
				(width 0)
				(type default)
			)
			(fill no)
			(layer "F.Fab")
		)
		(pad "1" smd custom
			(at 0 -0.4318 180)
			(size 0.127 0.127)
			(layers "F.Cu" "F.Mask" "F.Paste")
			(net "P3V3_STBY_VREG")
			(options
				(clearance outline)
				(anchor circle)
			)
			(primitives
				(gr_poly
					(pts
						(arc
							(start -0.2032 -0.2794)
							(mid -0.239121 -0.264521)
							(end -0.254 -0.2286)
						)
						(arc
							(start -0.254 0.2286)
							(mid -0.239121 0.264521)
							(end -0.2032 0.2794)
						)
						(arc
							(start 0.2032 0.2794)
							(mid 0.239121 0.264521)
							(end 0.254 0.2286)
						)
						(arc
							(start 0.254 -0.2286)
							(mid 0.239121 -0.264521)
							(end 0.2032 -0.2794)
						)
					)
					(width 0)
					(fill yes)
				)
			)
		)
		(pad "2" smd custom
			(at 0 0.4318 180)
			(size 0.127 0.127)
			(layers "F.Cu" "F.Mask" "F.Paste")
			(net "P3V3_STBY_RF")
			(options
				(clearance outline)
				(anchor circle)
			)
			(primitives
				(gr_poly
					(pts
						(arc
							(start -0.2032 -0.2794)
							(mid -0.239121 -0.264521)
							(end -0.254 -0.2286)
						)
						(arc
							(start -0.254 0.2286)
							(mid -0.239121 0.264521)
							(end -0.2032 0.2794)
						)
						(arc
							(start 0.2032 0.2794)
							(mid 0.239121 0.264521)
							(end 0.254 0.2286)
						)
						(arc
							(start 0.254 -0.2286)
							(mid 0.239121 -0.264521)
							(end 0.2032 -0.2794)
						)
					)
					(width 0)
					(fill yes)
				)
			)
		)
	)
	(footprint ""
		(layer "F.Cu")
		(at 128.143 -35.306 -90)
		(property "Reference" "R28"
			(at 0 0 270)
			(layer "F.SilkS")
			(hide yes)
			(effects
				(font
					(size 1.27 1.27)
				)
			)
		)
		(property "Value" "33R2F-3-GP"
			(at 0.064008 -3.993896 270)
			(unlocked yes)
			(layer "F.Fab")
			(hide yes)
			(effects
				(font
					(size 1.016 1.016)
					(thickness 0.1524)
				)
			)
		)
		(property "Device Type" "R402H16"
			(at 0.064008 -5.517896 270)
			(unlocked yes)
			(layer "F.Fab")
			(hide yes)
			(effects
				(font
					(size 1.016 1.016)
					(thickness 0.1524)
				)
			)
		)
		(duplicate_pad_numbers_are_jumpers no)
		(fp_rect
			(start -0.381 0.8382)
			(end 0.381 -0.8382)
			(stroke
				(width 0)
				(type default)
			)
			(fill no)
			(layer "F.CrtYd")
		)
		(fp_rect
			(start -0.381 0.8382)
			(end 0.381 -0.8382)
			(stroke
				(width 0)
				(type default)
			)
			(fill no)
			(layer "F.Fab")
		)
		(pad "1" smd custom
			(at 0 -0.4318 270)
			(size 0.127 0.127)
			(layers "F.Cu" "F.Mask" "F.Paste")
			(net "LPC_AD_0")
			(options
				(clearance outline)
				(anchor circle)
			)
			(primitives
				(gr_poly
					(pts
						(arc
							(start -0.2032 -0.2794)
							(mid -0.239121 -0.264521)
							(end -0.254 -0.2286)
						)
						(arc
							(start -0.254 0.2286)
							(mid -0.239121 0.264521)
							(end -0.2032 0.2794)
						)
						(arc
							(start 0.2032 0.2794)
							(mid 0.239121 0.264521)
							(end 0.254 0.2286)
						)
						(arc
							(start 0.254 -0.2286)
							(mid 0.239121 -0.264521)
							(end 0.2032 -0.2794)
						)
					)
					(width 0)
					(fill yes)
				)
			)
		)
		(pad "2" smd custom
			(at 0 0.4318 270)
			(size 0.127 0.127)
			(layers "F.Cu" "F.Mask" "F.Paste")
			(net "LPC_CPU_LAD0")
			(options
				(clearance outline)
				(anchor circle)
			)
			(primitives
				(gr_poly
					(pts
						(arc
							(start -0.2032 -0.2794)
							(mid -0.239121 -0.264521)
							(end -0.254 -0.2286)
						)
						(arc
							(start -0.254 0.2286)
							(mid -0.239121 0.264521)
							(end -0.2032 0.2794)
						)
						(arc
							(start 0.2032 0.2794)
							(mid 0.239121 0.264521)
							(end 0.254 0.2286)
						)
						(arc
							(start 0.254 -0.2286)
							(mid 0.239121 -0.264521)
							(end 0.2032 -0.2794)
						)
					)
					(width 0)
					(fill yes)
				)
			)
		)
	)
	(footprint ""
		(layer "F.Cu")
		(at 64.008 -52.578 -90)
		(property "Reference" "PR163"
			(at 0 0 270)
			(layer "F.SilkS")
			(hide yes)
			(effects
				(font
					(size 1.27 1.27)
				)
			)
		)
		(property "Value" "0R3J-6-GP"
			(at -0.0254 -2.0193 270)
			(unlocked yes)
			(layer "F.Fab")
			(hide yes)
			(effects
				(font
					(size 1.016 1.016)
					(thickness 0.1524)
				)
			)
		)
		(property "Device Type" "R603H22"
			(at -0.0254 -3.5433 270)
			(unlocked yes)
			(layer "F.Fab")
			(hide yes)
			(effects
				(font
					(size 1.016 1.016)
					(thickness 0.1524)
				)
			)
		)
		(duplicate_pad_numbers_are_jumpers no)
		(fp_line
			(start -0.2032 0)
			(end -0.4191 0)
			(stroke
				(width 0.2032)
				(type default)
			)
			(layer "F.SilkS")
		)
		(fp_line
			(start 0.4318 0)
			(end 0.2032 0)
			(stroke
				(width 0.2032)
				(type default)
			)
			(layer "F.SilkS")
		)
		(fp_rect
			(start -0.635 1.1811)
			(end 0.635 -1.1811)
			(stroke
				(width 0)
				(type default)
			)
			(fill no)
			(layer "F.CrtYd")
		)
		(fp_rect
			(start -0.635 1.1811)
			(end 0.635 -1.1811)
			(stroke
				(width 0)
				(type default)
			)
			(fill no)
			(layer "F.Fab")
		)
		(pad "1" smd custom
			(at 0 -0.6604 270)
			(size 0.19685 0.19685)
			(layers "F.Cu" "F.Mask" "F.Paste")
			(net "P1V0_STBY")
			(options
				(clearance outline)
				(anchor circle)
			)
			(primitives
				(gr_poly
					(pts
						(arc
							(start 0.508 -0.2921)
							(mid 0.478242 -0.363942)
							(end 0.4064 -0.3937)
						)
						(arc
							(start -0.4064 -0.3937)
							(mid -0.478242 -0.363942)
							(end -0.508 -0.2921)
						)
						(arc
							(start -0.508 0.2921)
							(mid -0.478242 0.363942)
							(end -0.4064 0.3937)
						)
						(arc
							(start 0.4064 0.3937)
							(mid 0.478242 0.363942)
							(end 0.508 0.2921)
						)
					)
					(width 0)
					(fill yes)
				)
			)
		)
		(pad "2" smd custom
			(at 0 0.6604 270)
			(size 0.19685 0.19685)
			(layers "F.Cu" "F.Mask" "F.Paste")
			(net "P1V0_STBY_VOUT")
			(options
				(clearance outline)
				(anchor circle)
			)
			(primitives
				(gr_poly
					(pts
						(arc
							(start 0.508 -0.2921)
							(mid 0.478242 -0.363942)
							(end 0.4064 -0.3937)
						)
						(arc
							(start -0.4064 -0.3937)
							(mid -0.478242 -0.363942)
							(end -0.508 -0.2921)
						)
						(arc
							(start -0.508 0.2921)
							(mid -0.478242 0.363942)
							(end -0.4064 0.3937)
						)
						(arc
							(start 0.4064 0.3937)
							(mid 0.478242 0.363942)
							(end 0.508 0.2921)
						)
					)
					(width 0)
					(fill yes)
				)
			)
		)
	)
	(footprint ""
		(layer "F.Cu")
		(at 155.575 -52.451)
		(property "Reference" "R286"
			(at 0 0 0)
			(layer "F.SilkS")
			(hide yes)
			(effects
				(font
					(size 1.27 1.27)
				)
			)
		)
		(property "Value" "33R2F-3-GP"
			(at 1.7907 -1.1176 0)
			(unlocked yes)
			(layer "F.Fab")
			(hide yes)
			(effects
				(font
					(size 1.016 1.016)
					(thickness 0.1524)
				)
			)
		)
		(property "Device Type" "R402H16"
			(at 1.7907 -2.6416 0)
			(unlocked yes)
			(layer "F.Fab")
			(hide yes)
			(effects
				(font
					(size 1.016 1.016)
					(thickness 0.1524)
				)
			)
		)
		(duplicate_pad_numbers_are_jumpers no)
		(fp_rect
			(start -0.381 0.8382)
			(end 0.381 -0.8382)
			(stroke
				(width 0)
				(type default)
			)
			(fill no)
			(layer "F.CrtYd")
		)
		(fp_rect
			(start -0.381 0.8382)
			(end 0.381 -0.8382)
			(stroke
				(width 0)
				(type default)
			)
			(fill no)
			(layer "F.Fab")
		)
		(pad "1" smd custom
			(at 0 -0.4318)
			(size 0.127 0.127)
			(layers "F.Cu" "F.Mask" "F.Paste")
			(net "C_R_DCLK")
			(options
				(clearance outline)
				(anchor circle)
			)
			(primitives
				(gr_poly
					(pts
						(arc
							(start -0.2032 -0.2794)
							(mid -0.239121 -0.264521)
							(end -0.254 -0.2286)
						)
						(arc
							(start -0.254 0.2286)
							(mid -0.239121 0.264521)
							(end -0.2032 0.2794)
						)
						(arc
							(start 0.2032 0.2794)
							(mid 0.239121 0.264521)
							(end 0.254 0.2286)
						)
						(arc
							(start 0.254 -0.2286)
							(mid 0.239121 -0.264521)
							(end 0.2032 -0.2794)
						)
					)
					(width 0)
					(fill yes)
				)
			)
		)
		(pad "2" smd custom
			(at 0 0.4318)
			(size 0.127 0.127)
			(layers "F.Cu" "F.Mask" "F.Paste")
			(net "C_DCLK")
			(options
				(clearance outline)
				(anchor circle)
			)
			(primitives
				(gr_poly
					(pts
						(arc
							(start -0.2032 -0.2794)
							(mid -0.239121 -0.264521)
							(end -0.254 -0.2286)
						)
						(arc
							(start -0.254 0.2286)
							(mid -0.239121 0.264521)
							(end -0.2032 0.2794)
						)
						(arc
							(start 0.2032 0.2794)
							(mid 0.239121 0.264521)
							(end 0.254 0.2286)
						)
						(arc
							(start 0.254 -0.2286)
							(mid 0.239121 -0.264521)
							(end 0.2032 -0.2794)
						)
					)
					(width 0)
					(fill yes)
				)
			)
		)
	)
	(footprint ""
		(layer "F.Cu")
		(at 82.423 -63.754 -90)
		(property "Reference" "R133"
			(at 0 0 270)
			(layer "F.SilkS")
			(hide yes)
			(effects
				(font
					(size 1.27 1.27)
				)
			)
		)
		(property "Value" "0R2J-2-GP"
			(at 0.064008 -3.993896 270)
			(unlocked yes)
			(layer "F.Fab")
			(hide yes)
			(effects
				(font
					(size 1.016 1.016)
					(thickness 0.1524)
				)
			)
		)
		(property "Device Type" "R402H16"
			(at 0.064008 -5.517896 270)
			(unlocked yes)
			(layer "F.Fab")
			(hide yes)
			(effects
				(font
					(size 1.016 1.016)
					(thickness 0.1524)
				)
			)
		)
		(duplicate_pad_numbers_are_jumpers no)
		(fp_rect
			(start -0.381 0.8382)
			(end 0.381 -0.8382)
			(stroke
				(width 0)
				(type default)
			)
			(fill no)
			(layer "F.CrtYd")
		)
		(fp_rect
			(start -0.381 0.8382)
			(end 0.381 -0.8382)
			(stroke
				(width 0)
				(type default)
			)
			(fill no)
			(layer "F.Fab")
		)
		(pad "1" smd custom
			(at 0 -0.4318 270)
			(size 0.127 0.127)
			(layers "F.Cu" "F.Mask" "F.Paste")
			(net "PV_VDDR")
			(options
				(clearance outline)
				(anchor circle)
			)
			(primitives
				(gr_poly
					(pts
						(arc
							(start -0.2032 -0.2794)
							(mid -0.239121 -0.264521)
							(end -0.254 -0.2286)
						)
						(arc
							(start -0.254 0.2286)
							(mid -0.239121 0.264521)
							(end -0.2032 0.2794)
						)
						(arc
							(start 0.2032 0.2794)
							(mid 0.239121 0.264521)
							(end 0.254 0.2286)
						)
						(arc
							(start 0.254 -0.2286)
							(mid 0.239121 -0.264521)
							(end 0.2032 -0.2794)
						)
					)
					(width 0)
					(fill yes)
				)
			)
		)
		(pad "2" smd custom
			(at 0 0.4318 270)
			(size 0.127 0.127)
			(layers "F.Cu" "F.Mask" "F.Paste")
			(net "PV_VDDR_SENSE")
			(options
				(clearance outline)
				(anchor circle)
			)
			(primitives
				(gr_poly
					(pts
						(arc
							(start -0.2032 -0.2794)
							(mid -0.239121 -0.264521)
							(end -0.254 -0.2286)
						)
						(arc
							(start -0.254 0.2286)
							(mid -0.239121 0.264521)
							(end -0.2032 0.2794)
						)
						(arc
							(start 0.2032 0.2794)
							(mid 0.239121 0.264521)
							(end 0.254 0.2286)
						)
						(arc
							(start 0.254 -0.2286)
							(mid 0.239121 -0.264521)
							(end 0.2032 -0.2794)
						)
					)
					(width 0)
					(fill yes)
				)
			)
		)
	)
)
